# S9S_MB_2U (Grand Teton) — schematic netlist excerpt (pin names and nets, part order shuffled) for the footprints in the layout excerpt that follows; sources: Cadence DE-HDL packaged netlist, KiCad conversion of 03242023_DA0F0TMBIJ0_F0T_Motherboard_J_brd_V01_OCP.brd

C1362  Q_CAP  22UF 4V 20% X6S  pkg C0402  page 76 : A = PVNN_MAIN_CPU0 ; B = GND
R818  Q_RES  0 5% CHIP  pkg 0402LF  page 130 : A = RST_PLD_CPU1_DRAM_EF_N ; B = RST_M_EF_CPU1_FPGA_N

(kicad_pcb
	(version 20260206)
	(generator "pcbnew")
	(generator_version "10.0")
	(general
		(thickness 1.6)
		(legacy_teardrops no)
	)
	(paper "A4")
	(title_block
		(title "03242023_DA0F0TMBIJ0_F0T_Motherboard_J_brd_V01_OCP.brd")
		(comment 1 "Grand Teton / footprints 5597-5598 of 6105")
	)
	(layers
		(0 "F.Cu" signal "TOP")
		(4 "In1.Cu" signal "GND")
		(6 "In2.Cu" signal "IN1")
		(8 "In3.Cu" signal "GND1")
		(10 "In4.Cu" signal "IN2")
		(12 "In5.Cu" signal "GND2")
		(14 "In6.Cu" signal "IN3")
		(16 "In7.Cu" signal "GND3")
		(18 "In8.Cu" signal "VCC")
		(20 "In9.Cu" signal "VCC1")
		(22 "In10.Cu" signal "GND4")
		(24 "In11.Cu" signal "IN4")
		(26 "In12.Cu" signal "GND5")
		(28 "In13.Cu" signal "IN5")
		(30 "In14.Cu" signal "GND6")
		(32 "In15.Cu" signal "IN6")
		(34 "In16.Cu" signal "GND7")
		(2 "B.Cu" signal "BOTTOM")
		(9 "F.Adhes" user "F.Adhesive")
		(11 "B.Adhes" user "B.Adhesive")
		(13 "F.Paste" user "Package Geometry/Pastemask Top")
		(15 "B.Paste" user "Package Geometry/Pastemask Bottom")
		(5 "F.SilkS" user "Ref Des/Silkscreen Top")
		(7 "B.SilkS" user "Ref Des/Silkscreen Bottom")
		(1 "F.Mask" user "Board Geometry/Soldermask Top")
		(3 "B.Mask" user "Board Geometry/Soldermask Bottom")
		(17 "Dwgs.User" user "User.Drawings")
		(19 "Cmts.User" user "User.Comments")
		(21 "Eco1.User" user "User.Eco1")
		(23 "Eco2.User" user "User.Eco2")
		(25 "Edge.Cuts" user "Board Geometry/Outline")
		(27 "Margin" user)
		(31 "F.CrtYd" user "Package Geometry/Place Bound Top")
		(29 "B.CrtYd" user "Package Geometry/Place Bound Bottom")
		(35 "F.Fab" user "Ref Des/Assembly Top")
		(33 "B.Fab" user "Ref Des/Assembly Bottom")
	)
	(footprint ""
		(layer "B.Cu")
		(at 354.446586 -235.916724)
		(property "Reference" "C1362"
			(at 0 0 0)
			(layer "B.SilkS")
			(hide yes)
			(effects
				(font
					(size 1.27 1.27)
				)
				(justify mirror)
			)
		)
		(property "Value" ""
			(at 0 0 0)
			(layer "B.Fab")
			(effects
				(font
					(size 1.27 1.27)
				)
				(justify mirror)
			)
		)
		(duplicate_pad_numbers_are_jumpers no)
		(fp_line
			(start -0.7874 -0.4064)
			(end -0.7874 0.4064)
			(stroke
				(width 0.1524)
				(type default)
			)
			(layer "B.SilkS")
		)
		(fp_line
			(start -0.7874 0.4064)
			(end 0.7874 0.4064)
			(stroke
				(width 0.1524)
				(type default)
			)
			(layer "B.SilkS")
		)
		(fp_line
			(start 0.7874 -0.4064)
			(end -0.7874 -0.4064)
			(stroke
				(width 0.1524)
				(type default)
			)
			(layer "B.SilkS")
		)
		(fp_line
			(start 0.7874 0.4064)
			(end 0.7874 -0.4064)
			(stroke
				(width 0.1524)
				(type default)
			)
			(layer "B.SilkS")
		)
		(fp_line
			(start -0.67945 -0.3048)
			(end -0.67945 0.3048)
			(stroke
				(width 0.1)
				(type default)
			)
			(layer "B.Fab")
		)
		(fp_line
			(start -0.67945 0.3048)
			(end -0.120396 0.3048)
			(stroke
				(width 0.1)
				(type default)
			)
			(layer "B.Fab")
		)
		(fp_line
			(start -0.12065 -0.3048)
			(end -0.67945 -0.3048)
			(stroke
				(width 0.1)
				(type default)
			)
			(layer "B.Fab")
		)
		(fp_line
			(start -0.12065 -0.2794)
			(end -0.12065 -0.3048)
			(stroke
				(width 0.1)
				(type default)
			)
			(layer "B.Fab")
		)
		(fp_line
			(start -0.120396 0.2794)
			(end 0.12065 0.2794)
			(stroke
				(width 0.1)
				(type default)
			)
			(layer "B.Fab")
		)
		(fp_line
			(start -0.120396 0.3048)
			(end -0.120396 0.2794)
			(stroke
				(width 0.1)
				(type default)
			)
			(layer "B.Fab")
		)
		(fp_line
			(start 0.12065 -0.305054)
			(end 0.12065 -0.2794)
			(stroke
				(width 0.1)
				(type default)
			)
			(layer "B.Fab")
		)
		(fp_line
			(start 0.12065 -0.2794)
			(end -0.12065 -0.2794)
			(stroke
				(width 0.1)
				(type default)
			)
			(layer "B.Fab")
		)
		(fp_line
			(start 0.12065 0.2794)
			(end 0.12065 0.3048)
			(stroke
				(width 0.1)
				(type default)
			)
			(layer "B.Fab")
		)
		(fp_line
			(start 0.12065 0.3048)
			(end 0.67945 0.3048)
			(stroke
				(width 0.1)
				(type default)
			)
			(layer "B.Fab")
		)
		(fp_line
			(start 0.67945 -0.305054)
			(end 0.12065 -0.305054)
			(stroke
				(width 0.1)
				(type default)
			)
			(layer "B.Fab")
		)
		(fp_line
			(start 0.67945 0.3048)
			(end 0.67945 -0.305054)
			(stroke
				(width 0.1)
				(type default)
			)
			(layer "B.Fab")
		)
		(pad "1" smd circle
			(at 0.40005 0 180)
			(size 0 0)
			(layers "B.Cu" "B.Mask" "B.Paste")
			(net "PVNN_MAIN_CPU0")
		)
		(pad "2" smd circle
			(at -0.40005 0 180)
			(size 0 0)
			(layers "B.Cu" "B.Mask" "B.Paste")
			(net "GND")
		)
	)
	(footprint ""
		(layer "B.Cu")
		(at 186.158886 -193.599816 -90)
		(property "Reference" "R818"
			(at 0 0 90)
			(layer "B.SilkS")
			(hide yes)
			(effects
				(font
					(size 1.27 1.27)
				)
				(justify mirror)
			)
		)
		(property "Value" ""
			(at 0 0 90)
			(layer "B.Fab")
			(effects
				(font
					(size 1.27 1.27)
				)
				(justify mirror)
			)
		)
		(duplicate_pad_numbers_are_jumpers no)
		(fp_line
			(start -0.7874 0.4064)
			(end 0.7874 0.4064)
			(stroke
				(width 0.1524)
				(type default)
			)
			(layer "B.SilkS")
		)
		(fp_line
			(start 0.7874 0.4064)
			(end 0.7874 -0.4064)
			(stroke
				(width 0.1524)
				(type default)
			)
			(layer "B.SilkS")
		)
		(fp_line
			(start -0.7874 -0.4064)
			(end -0.7874 0.4064)
			(stroke
				(width 0.1524)
				(type default)
			)
			(layer "B.SilkS")
		)
		(fp_line
			(start 0.7874 -0.4064)
			(end -0.7874 -0.4064)
			(stroke
				(width 0.1524)
				(type default)
			)
			(layer "B.SilkS")
		)
		(fp_line
			(start -0.67945 0.3048)
			(end -0.120396 0.3048)
			(stroke
				(width 0.1)
				(type default)
			)
			(layer "B.Fab")
		)
		(fp_line
			(start -0.120396 0.3048)
			(end -0.120396 0.2794)
			(stroke
				(width 0.1)
				(type default)
			)
			(layer "B.Fab")
		)
		(fp_line
			(start 0.12065 0.3048)
			(end 0.67945 0.3048)
			(stroke
				(width 0.1)
				(type default)
			)
			(layer "B.Fab")
		)
		(fp_line
			(start 0.67945 0.3048)
			(end 0.67945 -0.305054)
			(stroke
				(width 0.1)
				(type default)
			)
			(layer "B.Fab")
		)
		(fp_line
			(start -0.120396 0.2794)
			(end 0.12065 0.2794)
			(stroke
				(width 0.1)
				(type default)
			)
			(layer "B.Fab")
		)
		(fp_line
			(start 0.12065 0.2794)
			(end 0.12065 0.3048)
			(stroke
				(width 0.1)
				(type default)
			)
			(layer "B.Fab")
		)
		(fp_line
			(start -0.12065 -0.2794)
			(end -0.12065 -0.3048)
			(stroke
				(width 0.1)
				(type default)
			)
			(layer "B.Fab")
		)
		(fp_line
			(start 0.12065 -0.2794)
			(end -0.12065 -0.2794)
			(stroke
				(width 0.1)
				(type default)
			)
			(layer "B.Fab")
		)
		(fp_line
			(start -0.67945 -0.3048)
			(end -0.67945 0.3048)
			(stroke
				(width 0.1)
				(type default)
			)
			(layer "B.Fab")
		)
		(fp_line
			(start -0.12065 -0.3048)
			(end -0.67945 -0.3048)
			(stroke
				(width 0.1)
				(type default)
			)
			(layer "B.Fab")
		)
		(fp_line
			(start 0.12065 -0.305054)
			(end 0.12065 -0.2794)
			(stroke
				(width 0.1)
				(type default)
			)
			(layer "B.Fab")
		)
		(fp_line
			(start 0.67945 -0.305054)
			(end 0.12065 -0.305054)
			(stroke
				(width 0.1)
				(type default)
			)
			(layer "B.Fab")
		)
		(pad "1" smd circle
			(at 0.40005 0 90)
			(size 0 0)
			(layers "B.Cu" "B.Mask" "B.Paste")
			(net "RST_PLD_CPU1_DRAM_EF_N")
		)
		(pad "2" smd circle
			(at -0.40005 0 90)
			(size 0 0)
			(layers "B.Cu" "B.Mask" "B.Paste")
			(net "RST_M_EF_CPU1_FPGA_N")
		)
	)
)
